(kicad_pcb
	(version 20240108)
	(generator "pcbnew")
	(generator_version "8.0")
	(general
		(thickness 1.62)
		(legacy_teardrops no)
	)
	(paper "A4")
	(title_block
		(title "Jetson Orin Baseboard")
		(date "2025-03-12")
		(rev "1.3.4")
		(company "Antmicro Ltd")
		(comment 1 "www.antmicro.com")
		(comment 9 "footprints 237-239 of 677")
	)
	(layers
		(0 "F.Cu" signal)
		(1 "In1.Cu" signal)
		(2 "In2.Cu" signal)
		(3 "In3.Cu" signal)
		(4 "In4.Cu" jumper)
		(5 "In5.Cu" signal)
		(6 "In6.Cu" signal)
		(31 "B.Cu" signal)
		(32 "B.Adhes" user "B.Adhesive")
		(33 "F.Adhes" user "F.Adhesive")
		(34 "B.Paste" user)
		(35 "F.Paste" user)
		(36 "B.SilkS" user "B.Silkscreen")
		(37 "F.SilkS" user "F.Silkscreen")
		(38 "B.Mask" user)
		(39 "F.Mask" user)
		(40 "Dwgs.User" user "User.Drawings")
		(41 "Cmts.User" user "User.Comments")
		(42 "Eco1.User" user "User.Eco1")
		(43 "Eco2.User" user "User.Eco2")
		(44 "Edge.Cuts" user)
		(45 "Margin" user)
		(46 "B.CrtYd" user "B.Courtyard")
		(47 "F.CrtYd" user "F.Courtyard")
		(48 "B.Fab" user)
		(49 "F.Fab" user)
	)
	(footprint "antmicro-footprints:C_0402_1005Metric"
		(layer "F.Cu")
		(at 110.8 111.75 90)
		(descr "Capacitor SMD 0402")
		(tags "capacitor SMD 0402")
		(property "Reference" "C70"
			(at 0.8 0.5 90)
			(layer "F.SilkS")
			(effects
				(font
					(size 0.7 0.7)
					(thickness 0.15)
				)
				(justify left bottom)
			)
		)
		(property "Value" "C_100n_0402"
			(at 0 1.4 90)
			(layer "F.Fab")
			(effects
				(font
					(size 0.7 0.7)
					(thickness 0.15)
				)
				(justify left bottom)
			)
		)
		(property "Footprint" "antmicro-footprints:C_0402_1005Metric"
			(at 0 0 90)
			(layer "F.Fab")
			(hide yes)
			(effects
				(font
					(size 1.27 1.27)
					(thickness 0.15)
				)
			)
		)
		(property "Datasheet" "https://www.murata.com/products/productdetail?partno=GRM155R61H104KE14%23"
			(at 0 0 90)
			(layer "F.Fab")
			(hide yes)
			(effects
				(font
					(size 1.27 1.27)
					(thickness 0.15)
				)
			)
		)
		(property "Author" "Antmicro"
			(at 222.55 0.95 0)
			(layer "F.Fab")
			(hide yes)
			(effects
				(font
					(size 1 1)
					(thickness 0.15)
				)
			)
		)
		(property "Dielectric" "X5R"
			(at 222.55 0.95 0)
			(layer "F.Fab")
			(hide yes)
			(effects
				(font
					(size 1 1)
					(thickness 0.15)
				)
			)
		)
		(property "License" "Apache-2.0"
			(at 222.55 0.95 0)
			(layer "F.Fab")
			(hide yes)
			(effects
				(font
					(size 1 1)
					(thickness 0.15)
				)
			)
		)
		(property "MPN" "GRM155R61H104KE14D"
			(at 222.55 0.95 0)
			(layer "F.Fab")
			(hide yes)
			(effects
				(font
					(size 1 1)
					(thickness 0.15)
				)
			)
		)
		(property "Manufacturer" "Murata"
			(at 222.55 0.95 0)
			(layer "F.Fab")
			(hide yes)
			(effects
				(font
					(size 1 1)
					(thickness 0.15)
				)
			)
		)
		(property "Val" "100n"
			(at 222.55 0.95 0)
			(layer "F.Fab")
			(hide yes)
			(effects
				(font
					(size 1 1)
					(thickness 0.15)
				)
			)
		)
		(property "Voltage" "50V"
			(at 222.55 0.95 0)
			(layer "F.Fab")
			(hide yes)
			(effects
				(font
					(size 1 1)
					(thickness 0.15)
				)
			)
		)
		(sheetname "USB3")
		(sheetfile "usb3.kicad_sch")
		(attr smd)
		(fp_rect
			(start -0.925 -0.47)
			(end 0.925 0.47)
			(stroke
				(width 0.05)
				(type default)
			)
			(fill none)
			(layer "F.CrtYd")
		)
		(fp_line
			(start 0.504 -0.25)
			(end 0.504 0.248)
			(stroke
				(width 0.15)
				(type solid)
			)
			(layer "F.Fab")
		)
		(fp_line
			(start -0.494 -0.25)
			(end 0.504 -0.25)
			(stroke
				(width 0.15)
				(type solid)
			)
			(layer "F.Fab")
		)
		(fp_line
			(start 0.504 0.248)
			(end -0.494 0.248)
			(stroke
				(width 0.15)
				(type solid)
			)
			(layer "F.Fab")
		)
		(fp_line
			(start -0.494 0.248)
			(end -0.494 -0.25)
			(stroke
				(width 0.15)
				(type solid)
			)
			(layer "F.Fab")
		)
		(fp_text user "Author: Antmicro"
			(at -0.932 4.17 90)
			(layer "F.Fab")
			(hide yes)
			(effects
				(font
					(size 0.7 0.7)
					(thickness 0.15)
				)
				(justify left bottom)
			)
		)
		(fp_text user "${REFERENCE}"
			(at -0.932 3.168 90)
			(layer "F.Fab")
			(hide yes)
			(effects
				(font
					(size 0.7 0.7)
					(thickness 0.15)
				)
				(justify left bottom)
			)
		)
		(fp_text user "License: Apache-2.0"
			(at -0.932 5.17 90)
			(layer "F.Fab")
			(hide yes)
			(effects
				(font
					(size 0.7 0.7)
					(thickness 0.15)
				)
				(justify left bottom)
			)
		)
		(pad "1" smd roundrect
			(at -0.48 0 90)
			(size 0.59 0.64)
			(layers "F.Cu" "F.Paste" "F.Mask")
			(roundrect_rratio 0.25)
			(net 265 "/USB3/USBC1_CONN_TX1_N")
			(pintype "passive")
		)
		(pad "2" smd roundrect
			(at 0.48 0 90)
			(size 0.59 0.64)
			(layers "F.Cu" "F.Paste" "F.Mask")
			(roundrect_rratio 0.25)
			(net 264 "/USB3/USBC1_TX1_N")
			(pintype "passive")
		)
	)
	(footprint "antmicro-footprints:HDMI-Mini-C_Receptacle_WE_685119136923"
		(layer "F.Cu")
		(at 93.94 125.31)
		(property "Reference" "J13"
			(at 4.06 -3.56 0)
			(layer "F.SilkS")
			(effects
				(font
					(size 0.7 0.7)
					(thickness 0.15)
				)
				(justify left bottom)
			)
		)
		(property "Value" "HDMI-Mini-C_WE_685119136923"
			(at 0 5.251 0)
			(layer "F.Fab")
			(effects
				(font
					(size 0.7 0.7)
					(thickness 0.15)
				)
				(justify left bottom)
			)
		)
		(property "Footprint" "antmicro-footprints:HDMI-Mini-C_Receptacle_WE_685119136923"
			(at 0 0 0)
			(layer "F.Fab")
			(hide yes)
			(effects
				(font
					(size 1.27 1.27)
					(thickness 0.15)
				)
			)
		)
		(property "Datasheet" "https://www.we-online.com/components/products/datasheet/685119136923.pdf"
			(at 0 0 0)
			(layer "F.Fab")
			(hide yes)
			(effects
				(font
					(size 1.27 1.27)
					(thickness 0.15)
				)
			)
		)
		(property "Author" "Antmicro"
			(at 0 0 0)
			(layer "F.Fab")
			(hide yes)
			(effects
				(font
					(size 1 1)
					(thickness 0.15)
				)
			)
		)
		(property "License" "Apache-2.0"
			(at 0 0 0)
			(layer "F.Fab")
			(hide yes)
			(effects
				(font
					(size 1 1)
					(thickness 0.15)
				)
			)
		)
		(property "MPN" "685119136923"
			(at 0 0 0)
			(layer "F.Fab")
			(hide yes)
			(effects
				(font
					(size 1 1)
					(thickness 0.15)
				)
			)
		)
		(property "Manufacturer" "Würth Elektronik"
			(at 0 0 0)
			(layer "F.Fab")
			(hide yes)
			(effects
				(font
					(size 1 1)
					(thickness 0.15)
				)
			)
		)
		(sheetname "HDMI")
		(sheetfile "hdmi.kicad_sch")
		(attr smd)
		(fp_line
			(start -5.702 -1.301)
			(end -5.702 1.2)
			(stroke
				(width 0.15)
				(type solid)
			)
			(layer "F.SilkS")
		)
		(fp_line
			(start -3.9 -3.4)
			(end -5.702 -3.4)
			(stroke
				(width 0.15)
				(type solid)
			)
			(layer "F.SilkS")
		)
		(fp_line
			(start 3.898 -3.4)
			(end 5.7 -3.4)
			(stroke
				(width 0.15)
				(type solid)
			)
			(layer "F.SilkS")
		)
		(fp_line
			(start 5.7 -1.301)
			(end 5.7 1.2)
			(stroke
				(width 0.15)
				(type solid)
			)
			(layer "F.SilkS")
		)
		(fp_circle
			(center 3.9148 -3.7254)
			(end 3.9638 -3.7254)
			(stroke
				(width 0.15)
				(type solid)
			)
			(fill solid)
			(layer "F.SilkS")
		)
		(fp_line
			(start -6 -3.75)
			(end -6 4.3)
			(stroke
				(width 0.05)
				(type solid)
			)
			(layer "F.CrtYd")
		)
		(fp_line
			(start -6 4.3)
			(end 6 4.3)
			(stroke
				(width 0.05)
				(type solid)
			)
			(layer "F.CrtYd")
		)
		(fp_line
			(start -3.9 -4.019)
			(end -3.9 -3.75)
			(stroke
				(width 0.05)
				(type solid)
			)
			(layer "F.CrtYd")
		)
		(fp_line
			(start -3.9 -3.75)
			(end -6 -3.75)
			(stroke
				(width 0.05)
				(type solid)
			)
			(layer "F.CrtYd")
		)
		(fp_line
			(start 3.89 -4.019)
			(end -3.9 -4.019)
			(stroke
				(width 0.05)
				(type solid)
			)
			(layer "F.CrtYd")
		)
		(fp_line
			(start 3.89 -3.75)
			(end 3.89 -4.019)
			(stroke
				(width 0.05)
				(type solid)
			)
			(layer "F.CrtYd")
		)
		(fp_line
			(start 6 -3.75)
			(end 3.9 -3.75)
			(stroke
				(width 0.05)
				(type solid)
			)
			(layer "F.CrtYd")
		)
		(fp_line
			(start 6 4.3)
			(end 6 -3.75)
			(stroke
				(width 0.05)
				(type solid)
			)
			(layer "F.CrtYd")
		)
		(fp_line
			(start 4.8768 -3.579)
			(end 5.588 -2.9186)
			(stroke
				(width 0.15)
				(type solid)
			)
			(layer "F.Fab")
		)
		(fp_rect
			(start -5.6388 -3.579)
			(end 5.588 3.2282)
			(stroke
				(width 0.15)
				(type solid)
			)
			(fill none)
			(layer "F.Fab")
		)
		(fp_text user "Author: Antmicro"
			(at -6.125 13.54 0)
			(layer "F.Fab")
			(hide yes)
			(effects
				(font
					(size 0.7 0.7)
					(thickness 0.15)
				)
				(justify left bottom)
			)
		)
		(fp_text user "${REFERENCE}"
			(at -6.125 12.34 0)
			(layer "F.Fab")
			(hide yes)
			(effects
				(font
					(size 0.7 0.7)
					(thickness 0.15)
				)
				(justify left bottom)
			)
		)
		(fp_text user "License: Apache-2.0"
			(at -6.125 11.14 0)
			(layer "F.Fab")
			(hide yes)
			(effects
				(font
					(size 0.7 0.7)
					(thickness 0.15)
				)
				(justify left bottom)
			)
		)
		(pad "1" smd rect
			(at 3.6 -3.4)
			(size 0.23 1)
			(layers "F.Cu" "F.Paste" "F.Mask")
			(net 1 "GND")
			(pinfunction "D2S")
			(pintype "passive")
		)
		(pad "2" smd rect
			(at 3.2 -3.4)
			(size 0.23 1)
			(layers "F.Cu" "F.Paste" "F.Mask")
			(net 528 "/HDMI/HDMI_D2_CONN_P")
			(pinfunction "D2+")
			(pintype "bidirectional")
		)
		(pad "3" smd rect
			(at 2.798 -3.4)
			(size 0.23 1)
			(layers "F.Cu" "F.Paste" "F.Mask")
			(net 527 "/HDMI/HDMI_D2_CONN_N")
			(pinfunction "D2-")
			(pintype "bidirectional")
		)
		(pad "4" smd rect
			(at 2.398 -3.4)
			(size 0.23 1)
			(layers "F.Cu" "F.Paste" "F.Mask")
			(net 1 "GND")
			(pinfunction "D1S")
			(pintype "passive")
		)
		(pad "5" smd rect
			(at 1.999 -3.4)
			(size 0.23 1)
			(layers "F.Cu" "F.Paste" "F.Mask")
			(net 526 "/HDMI/HDMI_D1_CONN_P")
			(pinfunction "D1+")
			(pintype "bidirectional")
		)
		(pad "6" smd rect
			(at 1.6 -3.4)
			(size 0.23 1)
			(layers "F.Cu" "F.Paste" "F.Mask")
			(net 525 "/HDMI/HDMI_D1_CONN_N")
			(pinfunction "D1-")
			(pintype "bidirectional")
		)
		(pad "7" smd rect
			(at 1.199 -3.4)
			(size 0.23 1)
			(layers "F.Cu" "F.Paste" "F.Mask")
			(net 1 "GND")
			(pinfunction "D0S")
			(pintype "passive")
		)
		(pad "8" smd rect
			(at 0.8 -3.4)
			(size 0.23 1)
			(layers "F.Cu" "F.Paste" "F.Mask")
			(net 524 "/HDMI/HDMI_D0_CONN_P")
			(pinfunction "D0+")
			(pintype "bidirectional")
		)
		(pad "9" smd rect
			(at 0.4 -3.4)
			(size 0.23 1)
			(layers "F.Cu" "F.Paste" "F.Mask")
			(net 523 "/HDMI/HDMI_D0_CONN_N")
			(pinfunction "D0-")
			(pintype "bidirectional")
		)
		(pad "10" smd rect
			(at 0 -3.4)
			(size 0.23 1)
			(layers "F.Cu" "F.Paste" "F.Mask")
			(net 1 "GND")
			(pinfunction "CKS")
			(pintype "passive")
		)
		(pad "11" smd rect
			(at -0.402 -3.4)
			(size 0.23 1)
			(layers "F.Cu" "F.Paste" "F.Mask")
			(net 522 "/HDMI/HDMI_CLK_CONN_P")
			(pinfunction "CK+")
			(pintype "bidirectional")
		)
		(pad "12" smd rect
			(at -0.802 -3.4)
			(size 0.23 1)
			(layers "F.Cu" "F.Paste" "F.Mask")
			(net 521 "/HDMI/HDMI_CLK_CONN_N")
			(pinfunction "CK-")
			(pintype "bidirectional")
		)
		(pad "13" smd rect
			(at -1.2 -3.4)
			(size 0.23 1)
			(layers "F.Cu" "F.Paste" "F.Mask")
			(net 1 "GND")
			(pinfunction "GND")
			(pintype "power_in")
		)
		(pad "14" smd rect
			(at -1.601 -3.4)
			(size 0.23 1)
			(layers "F.Cu" "F.Paste" "F.Mask")
			(net 520 "/HDMI/HDMI_CEC_5V")
			(pinfunction "CEC")
			(pintype "bidirectional")
		)
		(pad "15" smd rect
			(at -2 -3.4)
			(size 0.23 1)
			(layers "F.Cu" "F.Paste" "F.Mask")
			(net 519 "/HDMI/HDMI_SCL_5V")
			(pinfunction "SCL")
			(pintype "bidirectional")
		)
		(pad "16" smd rect
			(at -2.4 -3.4)
			(size 0.23 1)
			(layers "F.Cu" "F.Paste" "F.Mask")
			(net 518 "/HDMI/HDMI_SDA_5V")
			(pinfunction "SDA")
			(pintype "bidirectional")
		)
		(pad "17" smd rect
			(at -2.801 -3.4)
			(size 0.23 1)
			(layers "F.Cu" "F.Paste" "F.Mask")
			(net 620 "unconnected-(J13-UTIL{slash}HEAC+-Pad17)")
			(pinfunction "UTIL/HEAC+")
			(pintype "bidirectional+no_connect")
		)
		(pad "18" smd rect
			(at -3.202 -3.4)
			(size 0.23 1)
			(layers "F.Cu" "F.Paste" "F.Mask")
			(net 498 "/HDMI/5V_HDMI")
			(pinfunction "+5V")
			(pintype "power_in")
		)
		(pad "19" smd rect
			(at -3.601 -3.4)
			(size 0.23 1)
			(layers "F.Cu" "F.Paste" "F.Mask")
			(net 529 "/HDMI/HDMI_HPD_5V")
			(pinfunction "HPD/HEAC-")
			(pintype "bidirectional")
		)
		(pad "SH" thru_hole oval
			(at -5.425 -2.35)
			(size 1.2 1.9)
			(drill oval 0.6 1.3)
			(layers "*.Cu" "*.Mask")
			(remove_unused_layers no)
			(net 1 "GND")
			(pinfunction "SH")
			(pintype "passive")
		)
		(pad "SH" thru_hole oval
			(at -5.425 2.15)
			(size 1.2 1.7)
			(drill oval 0.6 1.3)
			(layers "*.Cu" "*.Mask")
			(remove_unused_layers no)
			(net 1 "GND")
			(pinfunction "SH")
			(pintype "passive")
		)
		(pad "SH" thru_hole oval
			(at 5.424 -2.35)
			(size 1.2 1.9)
			(drill oval 0.6 1.3)
			(layers "*.Cu" "*.Mask")
			(remove_unused_layers no)
			(net 1 "GND")
			(pinfunction "SH")
			(pintype "passive")
		)
		(pad "SH" thru_hole oval
			(at 5.424 2.15)
			(size 1.2 1.7)
			(drill oval 0.6 1.3)
			(layers "*.Cu" "*.Mask")
			(remove_unused_layers no)
			(net 1 "GND")
			(pinfunction "SH")
			(pintype "passive")
		)
	)
	(footprint "antmicro-footprints:C_0402_1005Metric"
		(layer "F.Cu")
		(at 105.154938 108 180)
		(descr "Capacitor SMD 0402")
		(tags "capacitor SMD 0402")
		(property "Reference" "C68"
			(at 3.004938 -0.45 180)
			(layer "F.SilkS")
			(effects
				(font
					(size 0.7 0.7)
					(thickness 0.15)
				)
				(justify left bottom)
			)
		)
		(property "Value" "C_100n_0402"
			(at 0 1.4 180)
			(layer "F.Fab")
			(effects
				(font
					(size 0.7 0.7)
					(thickness 0.15)
				)
				(justify left bottom)
			)
		)
		(property "Footprint" "antmicro-footprints:C_0402_1005Metric"
			(at 0 0 180)
			(layer "F.Fab")
			(hide yes)
			(effects
				(font
					(size 1.27 1.27)
					(thickness 0.15)
				)
			)
		)
		(property "Datasheet" "https://www.murata.com/products/productdetail?partno=GRM155R61H104KE14%23"
			(at 0 0 180)
			(layer "F.Fab")
			(hide yes)
			(effects
				(font
					(size 1.27 1.27)
					(thickness 0.15)
				)
			)
		)
		(property "Author" "Antmicro"
			(at 210.309876 216 0)
			(layer "F.Fab")
			(hide yes)
			(effects
				(font
					(size 1 1)
					(thickness 0.15)
				)
			)
		)
		(property "Dielectric" "X5R"
			(at 210.309876 216 0)
			(layer "F.Fab")
			(hide yes)
			(effects
				(font
					(size 1 1)
					(thickness 0.15)
				)
			)
		)
		(property "License" "Apache-2.0"
			(at 210.309876 216 0)
			(layer "F.Fab")
			(hide yes)
			(effects
				(font
					(size 1 1)
					(thickness 0.15)
				)
			)
		)
		(property "MPN" "GRM155R61H104KE14D"
			(at 210.309876 216 0)
			(layer "F.Fab")
			(hide yes)
			(effects
				(font
					(size 1 1)
					(thickness 0.15)
				)
			)
		)
		(property "Manufacturer" "Murata"
			(at 210.309876 216 0)
			(layer "F.Fab")
			(hide yes)
			(effects
				(font
					(size 1 1)
					(thickness 0.15)
				)
			)
		)
		(property "Val" "100n"
			(at 210.309876 216 0)
			(layer "F.Fab")
			(hide yes)
			(effects
				(font
					(size 1 1)
					(thickness 0.15)
				)
			)
		)
		(property "Voltage" "50V"
			(at 210.309876 216 0)
			(layer "F.Fab")
			(hide yes)
			(effects
				(font
					(size 1 1)
					(thickness 0.15)
				)
			)
		)
		(sheetname "USB3")
		(sheetfile "usb3.kicad_sch")
		(attr smd)
		(fp_rect
			(start -0.925 -0.47)
			(end 0.925 0.47)
			(stroke
				(width 0.05)
				(type default)
			)
			(fill none)
			(layer "F.CrtYd")
		)
		(fp_line
			(start 0.504 0.248)
			(end -0.494 0.248)
			(stroke
				(width 0.15)
				(type solid)
			)
			(layer "F.Fab")
		)
		(fp_line
			(start 0.504 -0.25)
			(end 0.504 0.248)
			(stroke
				(width 0.15)
				(type solid)
			)
			(layer "F.Fab")
		)
		(fp_line
			(start -0.494 0.248)
			(end -0.494 -0.25)
			(stroke
				(width 0.15)
				(type solid)
			)
			(layer "F.Fab")
		)
		(fp_line
			(start -0.494 -0.25)
			(end 0.504 -0.25)
			(stroke
				(width 0.15)
				(type solid)
			)
			(layer "F.Fab")
		)
		(fp_text user "License: Apache-2.0"
			(at -0.932 5.17 180)
			(layer "F.Fab")
			(hide yes)
			(effects
				(font
					(size 0.7 0.7)
					(thickness 0.15)
				)
				(justify left bottom)
			)
		)
		(fp_text user "Author: Antmicro"
			(at -0.932 4.17 180)
			(layer "F.Fab")
			(hide yes)
			(effects
				(font
					(size 0.7 0.7)
					(thickness 0.15)
				)
				(justify left bottom)
			)
		)
		(fp_text user "${REFERENCE}"
			(at -0.932 3.168 180)
			(layer "F.Fab")
			(hide yes)
			(effects
				(font
					(size 0.7 0.7)
					(thickness 0.15)
				)
				(justify left bottom)
			)
		)
		(pad "1" smd roundrect
			(at -0.48 0 180)
			(size 0.59 0.64)
			(layers "F.Cu" "F.Paste" "F.Mask")
			(roundrect_rratio 0.25)
			(net 87 "+3V3")
			(pintype "passive")
		)
		(pad "2" smd roundrect
			(at 0.48 0 180)
			(size 0.59 0.64)
			(layers "F.Cu" "F.Paste" "F.Mask")
			(roundrect_rratio 0.25)
			(net 1 "GND")
			(pintype "passive")
		)
	)
)
